# S9S_MB_2U (Grand Teton) — schematic netlist excerpt (pin names and nets, part order shuffled) for the footprints in the layout excerpt that follows; sources: Cadence DE-HDL packaged netlist, KiCad conversion of 03242023_DA0F0TMBIJ0_F0T_Motherboard_J_brd_V01_OCP.brd

J29  SCONN288_ADR50017P130CC  SCONN288_ADR50017-P130CC IO  pkg DDR288S_1-1VXB  page 110
  VIN_BULK0  = P12V_S3_AUX_CPU1_NVDIMM
  RFU0  = TP_CHG_CPU1_DIMM1_FRU_0
  VIN_MGMT  = P3V3_AUX
  HSCL  = I3C_SPD_DDREFGH_CPU1_LVC1_SCL_4
  HSDA  = I3C_SPD_DDREFGH_CPU1_LVC1_SDA
  VSS0  = GND
  DQ0_A  = M_G_CPU1_SA_DQ<0>
  VSS1  = GND
  DQ1_A  = M_G_CPU1_SA_DQ<1>
  VSS2  = GND
  DQS0_A_T  = M_G_CPU1_SA_DQS_DP<0>
  DQS0_A_C  = M_G_CPU1_SA_DQS_DN<0>
  VSS3  = GND
  DQ4_A  = M_G_CPU1_SA_DQ<4>
  VSS4  = GND
  DQ5_A  = M_G_CPU1_SA_DQ<5>
  VSS5  = GND
  DQ8_A  = M_G_CPU1_SA_DQ<8>
  VSS6  = GND
  DQ9_A  = M_G_CPU1_SA_DQ<9>
  VSS7  = GND
  DQS1_A_T  = M_G_CPU1_SA_DQS_DP<1>
  DQS1_A_C  = M_G_CPU1_SA_DQS_DN<1>
  VSS8  = GND
  DQ12_A  = M_G_CPU1_SA_DQ<12>
  VSS9  = GND
  DQ13_A  = M_G_CPU1_SA_DQ<13>
  VSS10  = GND
  DQ16_A  = M_G_CPU1_SA_DQ<16>
  VSS11  = GND
  DQ17_A  = M_G_CPU1_SA_DQ<17>
  VSS12  = GND
  DQS2_A_T  = M_G_CPU1_SA_DQS_DP<2>
  DQS2_A_C  = M_G_CPU1_SA_DQS_DN<2>
  VSS13  = GND
  DQ20_A  = M_G_CPU1_SA_DQ<20>
  VSS14  = GND
  DQ21_A  = M_G_CPU1_SA_DQ<21>
  VSS15  = GND
  DQ24_A  = M_G_CPU1_SA_DQ<24>
  VSS16  = GND
  DQ25_A  = M_G_CPU1_SA_DQ<25>
  VSS17  = GND
  DQS3_A_T  = M_G_CPU1_SA_DQS_DP<3>
  DQS3_A_C  = M_G_CPU1_SA_DQS_DN<3>
  VSS18  = GND
  DQ28_A  = M_G_CPU1_SA_DQ<28>
  VSS19  = GND
  DQ29_A  = M_G_CPU1_SA_DQ<29>
  VSS20  = GND
  CB0_A  = M_G_CPU1_SA_CB<0>
  VSS21  = GND
  CB1_A  = M_G_CPU1_SA_CB<1>
  VSS22  = GND
  DQS4_A_T  = M_G_CPU1_SA_DQS_DP<4>
  DQS4_A_C  = M_G_CPU1_SA_DQS_DN<4>
  VSS23  = GND
  CB4_A  = M_G_CPU1_SA_CB<4>
  VSS24  = GND
  CB5_A  = M_G_CPU1_SA_CB<5>
  VSS25  = GND
  ALERT_N  = M_G_CPU1_ALERT_N
  VSS26  = GND
  CS0_A_N  = M_G_CPU1_SA_CS_N<0>
  VSS27  = GND
  CA0_A  = M_G_CPU1_SA_CA<0>
  VSS28  = GND
  CA2_A  = M_G_CPU1_SA_CA<2>
  VSS29  = GND
  CA4_A  = M_G_CPU1_SA_CA<4>
  VSS30  = GND
  CA6_A  = M_G_CPU1_SA_CA<6>
  VSS31  = GND
  PAR_A  = M_G_CPU1_SA_PAR
  VSS32  = GND
  CA0_B  = M_G_CPU1_SB_CA<0>
  VSS33  = GND
  CA2_B  = M_G_CPU1_SB_CA<2>
  VSS34  = GND
  CA4_B  = M_G_CPU1_SB_CA<4>
  VSS35  = GND
  CA6_B  = M_G_CPU1_SB_CA<6>
  VSS36  = GND
  CS0_B_N  = M_G_CPU1_SB_CS_N<0>
  VSS37  = GND
  \lbd||rsp_a_n\  = M_G_CPU1_SA_RSP<0>
  \lbs||rsp_b_n\  = M_G_CPU1_SB_RSP<0>
  VSS38  = GND
  CB4_B  = M_G_CPU1_SB_CB<4>
  VSS39  = GND
  CB5_B  = M_G_CPU1_SB_CB<5>
  VSS40  = GND
  \dqs9_b_t||tdqs9_b_t||dbi4_b_n\  = M_G_CPU1_SB_DQS_DP<9>
  \dqs9_b_c||tdqs9_b_c\  = M_G_CPU1_SB_DQS_DN<9>
  VSS41  = GND
  CB0_B  = M_G_CPU1_SB_CB<0>
  VSS42  = GND
  CB1_B  = M_G_CPU1_SB_CB<1>
  VSS43  = GND
  DQ0_B  = M_G_CPU1_SB_DQ<0>
  VSS44  = GND
  DQ1_B  = M_G_CPU1_SB_DQ<1>
  VSS45  = GND
  DQS0_B_T  = M_G_CPU1_SB_DQS_DP<0>
  DQS0_B_C  = M_G_CPU1_SB_DQS_DN<0>
  VSS46  = GND
  DQ4_B  = M_G_CPU1_SB_DQ<4>
  VSS47  = GND
  DQ5_B  = M_G_CPU1_SB_DQ<5>
  VSS48  = GND
  DQ8_B  = M_G_CPU1_SB_DQ<8>
  VSS49  = GND
  DQ9_B  = M_G_CPU1_SB_DQ<9>
  VSS50  = GND
  DQS1_B_T  = M_G_CPU1_SB_DQS_DP<1>
  DQS1_B_C  = M_G_CPU1_SB_DQS_DN<1>
  VSS51  = GND
  DQ12_B  = M_G_CPU1_SB_DQ<12>
  VSS52  = GND
  DQ13_B  = M_G_CPU1_SB_DQ<13>
  VSS53  = GND
  DQ16_B  = M_G_CPU1_SB_DQ<16>
  VSS54  = GND
  DQ17_B  = M_G_CPU1_SB_DQ<17>
  VSS55  = GND
  DQS2_B_T  = M_G_CPU1_SB_DQS_DP<2>
  DQS2_B_C  = M_G_CPU1_SB_DQS_DN<2>
  VSS56  = GND
  DQ20_B  = M_G_CPU1_SB_DQ<20>
  VSS57  = GND
  DQ21_B  = M_G_CPU1_SB_DQ<21>
  VSS58  = GND
  DQ24_B  = M_G_CPU1_SB_DQ<24>
  VSS59  = GND
  DQ25_B  = M_G_CPU1_SB_DQ<25>
  VSS60  = GND
  DQS3_B_T  = M_G_CPU1_SB_DQS_DP<3>
  DQS3_B_C  = M_G_CPU1_SB_DQS_DN<3>
  VSS61  = GND
  DQ28_B  = M_G_CPU1_SB_DQ<28>
  VSS62  = GND
  DQ29_B  = M_G_CPU1_SB_DQ<29>
  VSS63  = GND
  RFU1  = TP_CHG_CPU1_DIMM1_FRU_1
  VIN_BULK1  = P12V_S3_AUX_CPU1_NVDIMM
  VIN_BULK2  = P12V_S3_AUX_CPU1_NVDIMM
  \pwr_good||fail_n\  = PWRGD_CHG_CPU1_DIMM1
  HSA  = PD_CHG_CPU1_DIMM1_SAA
  RFU2  = TP_CHG_CPU1_DIMM1_FRU_2
  RFU3  = TP_CHG_CPU1_DIMM1_FRU_3
  VSS64  = GND
  DQ2_A  = M_G_CPU1_SA_DQ<2>
  VSS65  = GND
  DQ3_A  = M_G_CPU1_SA_DQ<3>
  VSS66  = GND
  \dqs5_a_c||tdqs5_a_c||dqs5_a_t||tdqs5_a_t\  = M_G_CPU1_SA_DQS_DN<5>
  \dqs5_a_t||tdqs5_a_t\  = M_G_CPU1_SA_DQS_DP<5>
  VSS67  = GND
  DQ6_A  = M_G_CPU1_SA_DQ<6>
  VSS68  = GND
  DQ7_A  = M_G_CPU1_SA_DQ<7>
  VSS69  = GND
  DQ10_A  = M_G_CPU1_SA_DQ<10>
  VSS70  = GND
  DQ11_A  = M_G_CPU1_SA_DQ<11>
  VSS71  = GND
  \dqs6_a_c||tdqs6_a_c||dqs6_a_t||tdqs6_a_t\  = M_G_CPU1_SA_DQS_DN<6>
  \dqs6_a_t||tdqs6_a_t\  = M_G_CPU1_SA_DQS_DP<6>
  VSS72  = GND
  DQ14_A  = M_G_CPU1_SA_DQ<14>
  VSS73  = GND
  DQ15_A  = M_G_CPU1_SA_DQ<15>
  VSS74  = GND
  DQ18_A  = M_G_CPU1_SA_DQ<18>
  VSS75  = GND
  DQ19_A  = M_G_CPU1_SA_DQ<19>
  VSS76  = GND
  \dqs7_a_c||tdqs7_a_c\  = M_G_CPU1_SA_DQS_DN<7>
  \dqs7_a_t||tdqs7_a_t\  = M_G_CPU1_SA_DQS_DP<7>
  VSS77  = GND
  DQ22_A  = M_G_CPU1_SA_DQ<22>
  VSS78  = GND
  DQ23_A  = M_G_CPU1_SA_DQ<23>
  VSS79  = GND
  DQ26_A  = M_G_CPU1_SA_DQ<26>
  VSS80  = GND
  DQ27_A  = M_G_CPU1_SA_DQ<27>
  VSS81  = GND
  \dqs8_a_c||tdqs8_a_c\  = M_G_CPU1_SA_DQS_DN<8>
  \dqs8_a_t||tdqs8_a_t\  = M_G_CPU1_SA_DQS_DP<8>
  VSS82  = GND
  DQ30_A  = M_G_CPU1_SA_DQ<30>
  VSS83  = GND
  DQ31_A  = M_G_CPU1_SA_DQ<31>
  VSS84  = GND
  CB2_A  = M_G_CPU1_SA_CB<2>
  VSS85  = GND
  CB3_A  = M_G_CPU1_SA_CB<3>
  VSS86  = GND
  \dqs9_a_c||tdqs9_a_c\  = M_G_CPU1_SA_DQS_DN<9>
  \dqs9_a_t||tdqs9_a_t\  = M_G_CPU1_SA_DQS_DP<9>
  VSS87  = GND
  CB6_A  = M_G_CPU1_SA_CB<6>
  VSS88  = GND
  CB7_A  = M_G_CPU1_SA_CB<7>
  VSS89  = GND
  RESET_N  = RST_M_GH_CPU1_FPGA_N
  VSS90  = GND
  CS1_A_N  = M_G_CPU1_SA_CS_N<1>
  VSS91  = GND
  CA1_A  = M_G_CPU1_SA_CA<1>
  VSS92  = GND
  CA3_A  = M_G_CPU1_SA_CA<3>
  VSS93  = GND
  CA5_A  = M_G_CPU1_SA_CA<5>
  VSS94  = GND
  CK_T  = M_G_CPU1_CLK_DP<0>
  CK_C  = M_G_CPU1_CLK_DN<0>
  VSS95  = GND
  RFU4  = TP_CHG_CPU1_DIMM1_FRU_4
  CA1_B  = M_G_CPU1_SB_CA<1>
  VSS96  = GND
  CA3_B  = M_G_CPU1_SB_CA<3>
  VSS97  = GND
  CA5_B  = M_G_CPU1_SB_CA<5>
  VSS98  = GND
  PAR_B  = M_G_CPU1_SB_PAR
  VSS99  = GND
  CS1_B_N  = M_G_CPU1_SB_CS_N<1>
  VSS100  = GND
  RFU5  = TP_CHG_CPU1_DIMM1_FRU_5
  RFU6  = TP_CHG_CPU1_DIMM1_FRU_6
  VSS101  = GND
  CB6_B  = M_G_CPU1_SB_CB<6>
  VSS102  = GND
  CB7_B  = M_G_CPU1_SB_CB<7>
  VSS103  = GND
  DQS4_B_C  = M_G_CPU1_SB_DQS_DN<4>
  DQS4_B_T  = M_G_CPU1_SB_DQS_DP<4>
  VSS104  = GND
  CB2_B  = M_G_CPU1_SB_CB<2>
  VSS105  = GND
  CB3_B  = M_G_CPU1_SB_CB<3>
  VSS106  = GND
  DQ2_B  = M_G_CPU1_SB_DQ<2>
  VSS107  = GND
  DQ3_B  = M_G_CPU1_SB_DQ<3>
  VSS108  = GND
  \dqs5_b_c||tdqs5_b_c\  = M_G_CPU1_SB_DQS_DN<5>
  \dqs5_b_t||tdqs5_b_t\  = M_G_CPU1_SB_DQS_DP<5>
  VSS109  = GND
  DQ6_B  = M_G_CPU1_SB_DQ<6>
  VSS110  = GND
  DQ7_B  = M_G_CPU1_SB_DQ<7>
  VSS111  = GND
  DQ10_B  = M_G_CPU1_SB_DQ<10>
  VSS112  = GND
  DQ11_B  = M_G_CPU1_SB_DQ<11>
  VSS113  = GND
  \dqs6_b_c||tdqs6_b_c\  = M_G_CPU1_SB_DQS_DN<6>
  \dqs6_b_t||tdqs6_b_t\  = M_G_CPU1_SB_DQS_DP<6>
  VSS114  = GND
  DQ14_B  = M_G_CPU1_SB_DQ<14>
  VSS115  = GND
  DQ15_B  = M_G_CPU1_SB_DQ<15>
  VSS116  = GND
  DQ18_B  = M_G_CPU1_SB_DQ<18>
  VSS117  = GND
  DQ19_B  = M_G_CPU1_SB_DQ<19>
  VSS118  = GND
  \dqs7_b_c||tdqs7_b_c\  = M_G_CPU1_SB_DQS_DN<7>
  \dqs7_b_t||tdqs7_b_t\  = M_G_CPU1_SB_DQS_DP<7>
  VSS119  = GND
  DQ22_B  = M_G_CPU1_SB_DQ<22>
  VSS120  = GND
  DQ23_B  = M_G_CPU1_SB_DQ<23>
  VSS121  = GND
  DQ26_B  = M_G_CPU1_SB_DQ<26>
  VSS122  = GND
  DQ27_B  = M_G_CPU1_SB_DQ<27>
  VSS123  = GND
  \dqs8_b_c||tdqs8_b_c\  = M_G_CPU1_SB_DQS_DN<8>
  \dqs8_b_t||tdqs8_b_t\  = M_G_CPU1_SB_DQS_DP<8>
  VSS124  = GND
  DQ30_B  = M_G_CPU1_SB_DQ<30>
  VSS125  = GND
  DQ31_B  = M_G_CPU1_SB_DQ<31>
  VSS126  = GND
  G1  = GND
  G2  = GND
  G3  = GND

(kicad_pcb
	(version 20260206)
	(generator "pcbnew")
	(generator_version "10.0")
	(general
		(thickness 1.6)
		(legacy_teardrops no)
	)
	(paper "A4")
	(title_block
		(title "03242023_DA0F0TMBIJ0_F0T_Motherboard_J_brd_V01_OCP.brd")
		(comment 1 "Grand Teton / footprint 2874 of 6105 (J29), pads 46-91 of 291")
	)
	(layers
		(0 "F.Cu" signal "TOP")
		(4 "In1.Cu" signal "GND")
		(6 "In2.Cu" signal "IN1")
		(8 "In3.Cu" signal "GND1")
		(10 "In4.Cu" signal "IN2")
		(12 "In5.Cu" signal "GND2")
		(14 "In6.Cu" signal "IN3")
		(16 "In7.Cu" signal "GND3")
		(18 "In8.Cu" signal "VCC")
		(20 "In9.Cu" signal "VCC1")
		(22 "In10.Cu" signal "GND4")
		(24 "In11.Cu" signal "IN4")
		(26 "In12.Cu" signal "GND5")
		(28 "In13.Cu" signal "IN5")
		(30 "In14.Cu" signal "GND6")
		(32 "In15.Cu" signal "IN6")
		(34 "In16.Cu" signal "GND7")
		(2 "B.Cu" signal "BOTTOM")
		(9 "F.Adhes" user "F.Adhesive")
		(11 "B.Adhes" user "B.Adhesive")
		(13 "F.Paste" user "Package Geometry/Pastemask Top")
		(15 "B.Paste" user "Package Geometry/Pastemask Bottom")
		(5 "F.SilkS" user "Ref Des/Silkscreen Top")
		(7 "B.SilkS" user "Ref Des/Silkscreen Bottom")
		(1 "F.Mask" user "Board Geometry/Soldermask Top")
		(3 "B.Mask" user "Board Geometry/Soldermask Bottom")
		(17 "Dwgs.User" user "User.Drawings")
		(19 "Cmts.User" user "User.Comments")
		(21 "Eco1.User" user "User.Eco1")
		(23 "Eco2.User" user "User.Eco2")
		(25 "Edge.Cuts" user "Board Geometry/Outline")
		(27 "Margin" user)
		(31 "F.CrtYd" user "Package Geometry/Place Bound Top")
		(29 "B.CrtYd" user "Package Geometry/Place Bound Bottom")
		(35 "F.Fab" user "Ref Des/Assembly Top")
		(33 "B.Fab" user "Ref Des/Assembly Bottom")
	)
	(footprint ""
		(layer "F.Cu")
		(at 198.58228 -258.091686)
		(property "Reference" "J29"
			(at -3.683 -81.702148 0)
			(unlocked yes)
			(layer "F.SilkS")
			(effects
				(font
					(size 0.7874 0.5842)
					(thickness 0.1524)
				)
				(justify left)
			)
		)
		(property "Value" ""
			(at 0 0 0)
			(layer "F.Fab")
			(effects
				(font
					(size 1.27 1.27)
				)
			)
		)
		(duplicate_pad_numbers_are_jumpers no)
		(pad "46" smd rect
			(at -2.050034 -25.07488 270)
			(size 0.519938 1.4986)
			(layers "F.Cu" "F.Mask" "F.Paste")
			(net "GND")
		)
		(pad "47" smd rect
			(at -2.050034 -24.224996 270)
			(size 0.519938 1.4986)
			(layers "F.Cu" "F.Mask" "F.Paste")
			(net "M_G_CPU1_SA_DQ<28>")
		)
		(pad "48" smd rect
			(at -2.050034 -23.375112 270)
			(size 0.519938 1.4986)
			(layers "F.Cu" "F.Mask" "F.Paste")
			(net "GND")
		)
		(pad "49" smd rect
			(at -2.050034 -22.524974 270)
			(size 0.519938 1.4986)
			(layers "F.Cu" "F.Mask" "F.Paste")
			(net "M_G_CPU1_SA_DQ<29>")
		)
		(pad "50" smd rect
			(at -2.050034 -21.67509 270)
			(size 0.519938 1.4986)
			(layers "F.Cu" "F.Mask" "F.Paste")
			(net "GND")
		)
		(pad "51" smd rect
			(at -2.050034 -20.824952 270)
			(size 0.519938 1.4986)
			(layers "F.Cu" "F.Mask" "F.Paste")
			(net "M_G_CPU1_SA_CB<0>")
		)
		(pad "52" smd rect
			(at -2.050034 -19.975068 270)
			(size 0.519938 1.4986)
			(layers "F.Cu" "F.Mask" "F.Paste")
			(net "GND")
		)
		(pad "53" smd rect
			(at -2.050034 -19.12493 270)
			(size 0.519938 1.4986)
			(layers "F.Cu" "F.Mask" "F.Paste")
			(net "M_G_CPU1_SA_CB<1>")
		)
		(pad "54" smd rect
			(at -2.050034 -18.275046 270)
			(size 0.519938 1.4986)
			(layers "F.Cu" "F.Mask" "F.Paste")
			(net "GND")
		)
		(pad "55" smd rect
			(at -2.050034 -17.424908 270)
			(size 0.519938 1.4986)
			(layers "F.Cu" "F.Mask" "F.Paste")
			(net "M_G_CPU1_SA_DQS_DP<4>")
		)
		(pad "56" smd rect
			(at -2.050034 -16.575024 270)
			(size 0.519938 1.4986)
			(layers "F.Cu" "F.Mask" "F.Paste")
			(net "M_G_CPU1_SA_DQS_DN<4>")
		)
		(pad "57" smd rect
			(at -2.050034 -15.724886 270)
			(size 0.519938 1.4986)
			(layers "F.Cu" "F.Mask" "F.Paste")
			(net "GND")
		)
		(pad "58" smd rect
			(at -2.050034 -14.875002 270)
			(size 0.519938 1.4986)
			(layers "F.Cu" "F.Mask" "F.Paste")
			(net "M_G_CPU1_SA_CB<4>")
		)
		(pad "59" smd rect
			(at -2.050034 -14.025118 270)
			(size 0.519938 1.4986)
			(layers "F.Cu" "F.Mask" "F.Paste")
			(net "GND")
		)
		(pad "60" smd rect
			(at -2.050034 -13.17498 270)
			(size 0.519938 1.4986)
			(layers "F.Cu" "F.Mask" "F.Paste")
			(net "M_G_CPU1_SA_CB<5>")
		)
		(pad "61" smd rect
			(at -2.050034 -12.325096 270)
			(size 0.519938 1.4986)
			(layers "F.Cu" "F.Mask" "F.Paste")
			(net "GND")
		)
		(pad "62" smd rect
			(at -2.050034 -11.474958 270)
			(size 0.519938 1.4986)
			(layers "F.Cu" "F.Mask" "F.Paste")
			(net "M_G_CPU1_ALERT_N")
		)
		(pad "63" smd rect
			(at -2.050034 -10.625074 270)
			(size 0.519938 1.4986)
			(layers "F.Cu" "F.Mask" "F.Paste")
			(net "GND")
		)
		(pad "64" smd rect
			(at -2.050034 -9.774936 270)
			(size 0.519938 1.4986)
			(layers "F.Cu" "F.Mask" "F.Paste")
			(net "M_G_CPU1_SA_CS_N<0>")
		)
		(pad "65" smd rect
			(at -2.050034 -8.925052 270)
			(size 0.519938 1.4986)
			(layers "F.Cu" "F.Mask" "F.Paste")
			(net "GND")
		)
		(pad "66" smd rect
			(at -2.050034 -8.074914 270)
			(size 0.519938 1.4986)
			(layers "F.Cu" "F.Mask" "F.Paste")
			(net "M_G_CPU1_SA_CA<0>")
		)
		(pad "67" smd rect
			(at -2.050034 -7.22503 270)
			(size 0.519938 1.4986)
			(layers "F.Cu" "F.Mask" "F.Paste")
			(net "GND")
		)
		(pad "68" smd rect
			(at -2.050034 -6.374892 270)
			(size 0.519938 1.4986)
			(layers "F.Cu" "F.Mask" "F.Paste")
			(net "M_G_CPU1_SA_CA<2>")
		)
		(pad "69" smd rect
			(at -2.050034 -5.525008 270)
			(size 0.519938 1.4986)
			(layers "F.Cu" "F.Mask" "F.Paste")
			(net "GND")
		)
		(pad "70" smd rect
			(at -2.050034 -4.675124 270)
			(size 0.519938 1.4986)
			(layers "F.Cu" "F.Mask" "F.Paste")
			(net "M_G_CPU1_SA_CA<4>")
		)
		(pad "71" smd rect
			(at -2.050034 -3.824986 270)
			(size 0.519938 1.4986)
			(layers "F.Cu" "F.Mask" "F.Paste")
			(net "GND")
		)
		(pad "72" smd rect
			(at -2.050034 -2.975102 270)
			(size 0.519938 1.4986)
			(layers "F.Cu" "F.Mask" "F.Paste")
			(net "M_G_CPU1_SA_CA<6>")
		)
		(pad "73" smd rect
			(at -2.050034 -2.124964 270)
			(size 0.519938 1.4986)
			(layers "F.Cu" "F.Mask" "F.Paste")
			(net "GND")
		)
		(pad "74" smd rect
			(at -2.050034 -1.27508 270)
			(size 0.519938 1.4986)
			(layers "F.Cu" "F.Mask" "F.Paste")
			(net "M_G_CPU1_SA_PAR")
		)
		(pad "75" smd rect
			(at -2.050034 -0.424942 270)
			(size 0.519938 1.4986)
			(layers "F.Cu" "F.Mask" "F.Paste")
			(net "GND")
		)
		(pad "76" smd rect
			(at -2.050034 5.525008 270)
			(size 0.519938 1.4986)
			(layers "F.Cu" "F.Mask" "F.Paste")
			(net "M_G_CPU1_SB_CA<0>")
		)
		(pad "77" smd rect
			(at -2.050034 6.374892 270)
			(size 0.519938 1.4986)
			(layers "F.Cu" "F.Mask" "F.Paste")
			(net "GND")
		)
		(pad "78" smd rect
			(at -2.050034 7.22503 270)
			(size 0.519938 1.4986)
			(layers "F.Cu" "F.Mask" "F.Paste")
			(net "M_G_CPU1_SB_CA<2>")
		)
		(pad "79" smd rect
			(at -2.050034 8.074914 270)
			(size 0.519938 1.4986)
			(layers "F.Cu" "F.Mask" "F.Paste")
			(net "GND")
		)
		(pad "80" smd rect
			(at -2.050034 8.925052 270)
			(size 0.519938 1.4986)
			(layers "F.Cu" "F.Mask" "F.Paste")
			(net "M_G_CPU1_SB_CA<4>")
		)
		(pad "81" smd rect
			(at -2.050034 9.774936 270)
			(size 0.519938 1.4986)
			(layers "F.Cu" "F.Mask" "F.Paste")
			(net "GND")
		)
		(pad "82" smd rect
			(at -2.050034 10.625074 270)
			(size 0.519938 1.4986)
			(layers "F.Cu" "F.Mask" "F.Paste")
			(net "M_G_CPU1_SB_CA<6>")
		)
		(pad "83" smd rect
			(at -2.050034 11.474958 270)
			(size 0.519938 1.4986)
			(layers "F.Cu" "F.Mask" "F.Paste")
			(net "GND")
		)
		(pad "84" smd rect
			(at -2.050034 12.325096 270)
			(size 0.519938 1.4986)
			(layers "F.Cu" "F.Mask" "F.Paste")
			(net "M_G_CPU1_SB_CS_N<0>")
		)
		(pad "85" smd rect
			(at -2.050034 13.17498 270)
			(size 0.519938 1.4986)
			(layers "F.Cu" "F.Mask" "F.Paste")
			(net "GND")
		)
		(pad "86" smd rect
			(at -2.050034 14.025118 270)
			(size 0.519938 1.4986)
			(layers "F.Cu" "F.Mask" "F.Paste")
			(net "M_G_CPU1_SA_RSP<0>")
		)
		(pad "87" smd rect
			(at -2.050034 14.875002 270)
			(size 0.519938 1.4986)
			(layers "F.Cu" "F.Mask" "F.Paste")
			(net "M_G_CPU1_SB_RSP<0>")
		)
		(pad "88" smd rect
			(at -2.050034 15.724886 270)
			(size 0.519938 1.4986)
			(layers "F.Cu" "F.Mask" "F.Paste")
			(net "GND")
		)
		(pad "89" smd rect
			(at -2.050034 16.575024 270)
			(size 0.519938 1.4986)
			(layers "F.Cu" "F.Mask" "F.Paste")
			(net "M_G_CPU1_SB_CB<4>")
		)
		(pad "90" smd rect
			(at -2.050034 17.424908 270)
			(size 0.519938 1.4986)
			(layers "F.Cu" "F.Mask" "F.Paste")
			(net "GND")
		)
		(pad "91" smd rect
			(at -2.050034 18.275046 270)
			(size 0.519938 1.4986)
			(layers "F.Cu" "F.Mask" "F.Paste")
			(net "M_G_CPU1_SB_CB<5>")
		)
	)
)
